# T6G (Grand Teton) — schematic netlist excerpt (pin names and nets, part order shuffled) for the footprints in the layout excerpt that follows; sources: Cadence DE-HDL packaged netlist, KiCad conversion of 04192023_DAF0TMB3IC0_F0TG_MB_C_brd_V02_OCP.brd

R1305  Q_RES  4.7K 1% EMPTY  pkg 0402LF  page 357 : A = GND ; B = INA230_8_A1
R1113  Q_RES  10K 1% CHIP  pkg 0201LF  page 309 : A = GPIO3_RT_CPU0_P3 ; B = GND
C1868  Q_CAP  0.1UF 25V 10% X7R  pkg 0402  page 113 : A = P2E_MB_BMC_RX_BUF_C_DP<0> ; B = P2E_MB_BMC_RX_BUF_DP<0>

(kicad_pcb
	(version 20260206)
	(generator "pcbnew")
	(generator_version "10.0")
	(general
		(thickness 1.6)
		(legacy_teardrops no)
	)
	(paper "A4")
	(title_block
		(title "04192023_DAF0TMB3IC0_F0TG_MB_C_brd_V02_OCP.brd")
		(comment 1 "Grand Teton / footprints 1604-1606 of 8354")
	)
	(layers
		(0 "F.Cu" signal "TOP")
		(4 "In1.Cu" signal "GND")
		(6 "In2.Cu" signal "IN1")
		(8 "In3.Cu" signal "GND1")
		(10 "In4.Cu" signal "IN2")
		(12 "In5.Cu" signal "GND2")
		(14 "In6.Cu" signal "IN3")
		(16 "In7.Cu" signal "GND3")
		(18 "In8.Cu" signal "VCC")
		(20 "In9.Cu" signal "VCC1")
		(22 "In10.Cu" signal "GND4")
		(24 "In11.Cu" signal "IN4")
		(26 "In12.Cu" signal "GND5")
		(28 "In13.Cu" signal "IN5")
		(30 "In14.Cu" signal "GND6")
		(32 "In15.Cu" signal "IN6")
		(34 "In16.Cu" signal "GND7")
		(2 "B.Cu" signal "BOTTOM")
		(9 "F.Adhes" user "F.Adhesive")
		(11 "B.Adhes" user "B.Adhesive")
		(13 "F.Paste" user "Package Geometry/Pastemask Top")
		(15 "B.Paste" user "Package Geometry/Pastemask Bottom")
		(5 "F.SilkS" user "Ref Des/Silkscreen Top")
		(7 "B.SilkS" user "Ref Des/Silkscreen Bottom")
		(1 "F.Mask" user "Board Geometry/Soldermask Top")
		(3 "B.Mask" user "Board Geometry/Soldermask Bottom")
		(17 "Dwgs.User" user "User.Drawings")
		(19 "Cmts.User" user "User.Comments")
		(21 "Eco1.User" user "User.Eco1")
		(23 "Eco2.User" user "User.Eco2")
		(25 "Edge.Cuts" user "Board Geometry/Outline")
		(27 "Margin" user)
		(31 "F.CrtYd" user "Package Geometry/Place Bound Top")
		(29 "B.CrtYd" user "Package Geometry/Place Bound Bottom")
		(35 "F.Fab" user "Ref Des/Assembly Top")
		(33 "B.Fab" user "Ref Des/Assembly Bottom")
	)
	(footprint ""
		(layer "F.Cu")
		(at 39.15029 -426.563536)
		(property "Reference" "C1868"
			(at 0 0 0)
			(layer "F.SilkS")
			(hide yes)
			(effects
				(font
					(size 1.27 1.27)
				)
			)
		)
		(property "Value" ""
			(at 0 0 0)
			(layer "F.Fab")
			(effects
				(font
					(size 1.27 1.27)
				)
			)
		)
		(duplicate_pad_numbers_are_jumpers no)
		(fp_line
			(start -0.7874 -0.4064)
			(end 0.7874 -0.4064)
			(stroke
				(width 0.1524)
				(type default)
			)
			(layer "F.SilkS")
		)
		(fp_line
			(start -0.33909 0.4064)
			(end -0.7874 0.4064)
			(stroke
				(width 0.1524)
				(type default)
			)
			(layer "F.SilkS")
		)
		(fp_line
			(start 0.7874 -0.4064)
			(end 0.7874 0.275336)
			(stroke
				(width 0.1524)
				(type default)
			)
			(layer "F.SilkS")
		)
		(fp_line
			(start -0.6858 -0.3048)
			(end -0.1016 -0.3048)
			(stroke
				(width 0.1)
				(type default)
			)
			(layer "F.Fab")
		)
		(fp_line
			(start -0.6858 0.3048)
			(end -0.6858 -0.3048)
			(stroke
				(width 0.1)
				(type default)
			)
			(layer "F.Fab")
		)
		(fp_line
			(start -0.1016 -0.3048)
			(end -0.1016 -0.2794)
			(stroke
				(width 0.1)
				(type default)
			)
			(layer "F.Fab")
		)
		(fp_line
			(start -0.1016 -0.2794)
			(end 0.1016 -0.2794)
			(stroke
				(width 0.1)
				(type default)
			)
			(layer "F.Fab")
		)
		(fp_line
			(start -0.1016 0.2794)
			(end -0.1016 0.3048)
			(stroke
				(width 0.1)
				(type default)
			)
			(layer "F.Fab")
		)
		(fp_line
			(start -0.1016 0.3048)
			(end -0.6858 0.3048)
			(stroke
				(width 0.1)
				(type default)
			)
			(layer "F.Fab")
		)
		(fp_line
			(start 0.1016 -0.3048)
			(end 0.6858 -0.3048)
			(stroke
				(width 0.1)
				(type default)
			)
			(layer "F.Fab")
		)
		(fp_line
			(start 0.1016 -0.2794)
			(end 0.1016 -0.3048)
			(stroke
				(width 0.1)
				(type default)
			)
			(layer "F.Fab")
		)
		(fp_line
			(start 0.1016 0.2794)
			(end -0.1016 0.2794)
			(stroke
				(width 0.1)
				(type default)
			)
			(layer "F.Fab")
		)
		(fp_line
			(start 0.1016 0.3048)
			(end 0.1016 0.2794)
			(stroke
				(width 0.1)
				(type default)
			)
			(layer "F.Fab")
		)
		(fp_line
			(start 0.6858 -0.3048)
			(end 0.6858 0.3048)
			(stroke
				(width 0.1)
				(type default)
			)
			(layer "F.Fab")
		)
		(fp_line
			(start 0.6858 0.3048)
			(end 0.1016 0.3048)
			(stroke
				(width 0.1)
				(type default)
			)
			(layer "F.Fab")
		)
		(pad "1" smd rect
			(at -0.40005 0 180)
			(size 0.4572 0.508)
			(layers "F.Cu" "F.Mask" "F.Paste")
			(net "P2E_MB_BMC_RX_BUF_C_DP<0>")
		)
		(pad "2" smd rect
			(at 0.40005 0 180)
			(size 0.4572 0.508)
			(layers "F.Cu" "F.Mask" "F.Paste")
			(net "P2E_MB_BMC_RX_BUF_DP<0>")
		)
	)
	(footprint ""
		(layer "F.Cu")
		(at 366.36579 -393.04468)
		(property "Reference" "R1113"
			(at 0 0 0)
			(layer "F.SilkS")
			(hide yes)
			(effects
				(font
					(size 1.27 1.27)
				)
			)
		)
		(property "Value" ""
			(at 0 0 0)
			(layer "F.Fab")
			(effects
				(font
					(size 1.27 1.27)
				)
			)
		)
		(duplicate_pad_numbers_are_jumpers no)
		(fp_line
			(start -0.32512 -0.175006)
			(end 0.32512 -0.175006)
			(stroke
				(width 0.1)
				(type default)
			)
			(layer "F.Fab")
		)
		(fp_line
			(start -0.32512 0.175006)
			(end -0.32512 -0.175006)
			(stroke
				(width 0.1)
				(type default)
			)
			(layer "F.Fab")
		)
		(fp_line
			(start 0.32512 -0.175006)
			(end 0.32512 0.175006)
			(stroke
				(width 0.1)
				(type default)
			)
			(layer "F.Fab")
		)
		(fp_line
			(start 0.32512 0.175006)
			(end -0.32512 0.175006)
			(stroke
				(width 0.1)
				(type default)
			)
			(layer "F.Fab")
		)
		(pad "1" smd rect
			(at -0.2667 0)
			(size 0.3048 0.381)
			(layers "F.Cu" "F.Mask" "F.Paste")
			(net "GPIO3_RT_CPU0_P3")
		)
		(pad "2" smd rect
			(at 0.2667 0 180)
			(size 0.3048 0.381)
			(layers "F.Cu" "F.Mask" "F.Paste")
			(net "GND")
		)
	)
	(footprint ""
		(layer "F.Cu")
		(at 321.107308 -104.42575)
		(property "Reference" "R1305"
			(at 0 0 0)
			(layer "F.SilkS")
			(hide yes)
			(effects
				(font
					(size 1.27 1.27)
				)
			)
		)
		(property "Value" ""
			(at 0 0 0)
			(layer "F.Fab")
			(effects
				(font
					(size 1.27 1.27)
				)
			)
		)
		(duplicate_pad_numbers_are_jumpers no)
		(fp_line
			(start -0.7874 -0.4064)
			(end 0.7874 -0.4064)
			(stroke
				(width 0.1524)
				(type default)
			)
			(layer "F.SilkS")
		)
		(fp_line
			(start -0.7874 0.4064)
			(end -0.7874 -0.4064)
			(stroke
				(width 0.1524)
				(type default)
			)
			(layer "F.SilkS")
		)
		(fp_line
			(start 0.7874 -0.4064)
			(end 0.7874 0.4064)
			(stroke
				(width 0.1524)
				(type default)
			)
			(layer "F.SilkS")
		)
		(fp_line
			(start 0.7874 0.4064)
			(end -0.7874 0.4064)
			(stroke
				(width 0.1524)
				(type default)
			)
			(layer "F.SilkS")
		)
		(fp_line
			(start -0.67945 -0.305054)
			(end -0.12065 -0.305054)
			(stroke
				(width 0.1)
				(type default)
			)
			(layer "F.Fab")
		)
		(fp_line
			(start -0.67945 0.3048)
			(end -0.67945 -0.305054)
			(stroke
				(width 0.1)
				(type default)
			)
			(layer "F.Fab")
		)
		(fp_line
			(start -0.12065 -0.305054)
			(end -0.12065 -0.2794)
			(stroke
				(width 0.1)
				(type default)
			)
			(layer "F.Fab")
		)
		(fp_line
			(start -0.12065 -0.2794)
			(end 0.12065 -0.2794)
			(stroke
				(width 0.1)
				(type default)
			)
			(layer "F.Fab")
		)
		(fp_line
			(start -0.12065 0.2794)
			(end -0.12065 0.3048)
			(stroke
				(width 0.1)
				(type default)
			)
			(layer "F.Fab")
		)
		(fp_line
			(start -0.12065 0.3048)
			(end -0.67945 0.3048)
			(stroke
				(width 0.1)
				(type default)
			)
			(layer "F.Fab")
		)
		(fp_line
			(start 0.120396 0.2794)
			(end -0.12065 0.2794)
			(stroke
				(width 0.1)
				(type default)
			)
			(layer "F.Fab")
		)
		(fp_line
			(start 0.120396 0.3048)
			(end 0.120396 0.2794)
			(stroke
				(width 0.1)
				(type default)
			)
			(layer "F.Fab")
		)
		(fp_line
			(start 0.12065 -0.3048)
			(end 0.67945 -0.3048)
			(stroke
				(width 0.1)
				(type default)
			)
			(layer "F.Fab")
		)
		(fp_line
			(start 0.12065 -0.2794)
			(end 0.12065 -0.3048)
			(stroke
				(width 0.1)
				(type default)
			)
			(layer "F.Fab")
		)
		(fp_line
			(start 0.67945 -0.3048)
			(end 0.67945 0.3048)
			(stroke
				(width 0.1)
				(type default)
			)
			(layer "F.Fab")
		)
		(fp_line
			(start 0.67945 0.3048)
			(end 0.120396 0.3048)
			(stroke
				(width 0.1)
				(type default)
			)
			(layer "F.Fab")
		)
		(pad "1" smd circle
			(at -0.40005 0)
			(size 0 0)
			(layers "F.Cu" "F.Mask" "F.Paste")
			(net "GND")
		)
		(pad "2" smd circle
			(at 0.40005 0)
			(size 0 0)
			(layers "F.Cu" "F.Mask" "F.Paste")
			(net "INA230_8_A1")
		)
	)
)
